#ISCELL
  mstr_symbols intel_corp_bpage *
  *
#ISCELL
  mstr_symbols gnd *
  page242_i1
#ISCELL
  mstr_symbols gnd *
  page242_i10
#ISCELL
  mstr_symbols pvddq_abc *
  page242_i26
#ISCELL
  mstr_symbols gnd *
  page242_i27
#ISCELL
  mstr_symbols pvddq_def *
  page242_i29
#ISCELL
  mstr_symbols pvddq_abc *
  page242_i3
#ISCELL
  mstr_symbols gnd *
  page242_i33
#ISCELL
  mstr_symbols pvddq_def *
  page242_i35
#ISCELL
  mstr_symbols gnd *
  page242_i36
#ISCELL
  mstr_symbols pvddq_def *
  page242_i50
#CELL
  dev_discrete cap_a *
  page242_i53
#CELL
  dev_discrete cap_a *
  page242_i54
#CELL
  dev_discrete cap_a *
  page242_i55
#CELL
  dev_discrete cap_a *
  page242_i56
#CELL
  dev_discrete cap_a *
  page242_i57
#CELL
  dev_discrete cap_a *
  page242_i58
#CELL
  dev_discrete cap_a *
  page242_i59
#CELL
  dev_discrete cap_a *
  page242_i60
#CELL
  dev_discrete cap_a *
  page242_i61
#CELL
  dev_discrete cap_a *
  page242_i62
#CELL
  dev_discrete cap_a *
  page242_i63
#CELL
  dev_discrete cap_a *
  page242_i64
#CELL
  dev_discrete cap_a *
  page242_i65
#CELL
  dev_discrete cap_a *
  page242_i66
#CELL
  dev_discrete cap_a *
  page242_i67
#CELL
  dev_discrete cap_a *
  page242_i68
#CELL
  dev_discrete cap_a *
  page242_i69
#ISCELL
  mstr_symbols gnd *
  page242_i7
#CELL
  dev_discrete cap_a *
  page242_i70
#CELL
  dev_discrete cap_a *
  page242_i71
#CELL
  dev_discrete cap_a *
  page242_i72
#CELL
  dev_discrete cap_a *
  page242_i73
#CELL
  dev_discrete cap_a *
  page242_i74
#CELL
  dev_discrete cap_a *
  page242_i75
#CELL
  dev_discrete cap_a *
  page242_i76
#CELL
  dev_discrete cap_a *
  page242_i77
#CELL
  dev_discrete cap_a *
  page242_i78
#CELL
  dev_discrete cap_a *
  page242_i79
#CELL
  dev_discrete cap_a *
  page242_i80
#CELL
  dev_discrete cap_a *
  page242_i81
#CELL
  dev_discrete cap_a *
  page242_i82
#CELL
  dev_discrete cap_a *
  page242_i83
#CELL
  dev_discrete cap_a *
  page242_i84
#CELL
  dev_discrete cap_a *
  page242_i85
#CELL
  dev_discrete cap_a *
  page242_i86
#CELL
  dev_discrete cap_a *
  page242_i87
#CELL
  dev_discrete cap_a *
  page242_i88
#CELL
  mstr_discrete cap *
  page242_i89
#ISCELL
  mstr_symbols pvddq_abc *
  page242_i9
#CELL
  mstr_discrete cap *
  page242_i90
#CELL
  mstr_discrete cap *
  page242_i91
#CELL
  mstr_discrete cap *
  page242_i92
